# TIMECARD (Time Appliance Project (Time Card)) — schematic netlist excerpt (pin names and nets, part order shuffled) for the footprints in the layout excerpt that follows; sources: Cadence DE-HDL packaged netlist, KiCad conversion of R4006-B0001-02_R01.brd

R275  RESISTOR  100OHM 1%  pkg SMC_0402R_H016  page 13 : \1\ = FPGA_IN_MAC_PPS_OUTP ; \2\ = FPGA_IN_MAC_PPS_OUTN
R250  RESISTOR  0OHM -  pkg SMC_0402R_H016  page 29 : \1\ = XP1R0V_BT ; \2\ = UNNAMED_523_CAPACITOR_I24_1

(kicad_pcb
	(version 20260206)
	(generator "pcbnew")
	(generator_version "10.0")
	(general
		(thickness 1.6)
		(legacy_teardrops no)
	)
	(paper "A4")
	(title_block
		(title "timecard-production-celestica-r4006 — R4006-B0001-02_R01.brd")
		(comment 1 "Time Appliance Project (Time Card) / footprints 683-684 of 1113")
	)
	(layers
		(0 "F.Cu" signal "TOP")
		(4 "In1.Cu" signal "L02_GND1")
		(6 "In2.Cu" signal "L03_SIG1")
		(8 "In3.Cu" signal "L04_GND2")
		(10 "In4.Cu" signal "L05_VCC1")
		(12 "In5.Cu" signal "L06_VCC2")
		(14 "In6.Cu" signal "L07_GND3")
		(16 "In7.Cu" signal "L08_SIG2")
		(18 "In8.Cu" signal "L09_GND4")
		(2 "B.Cu" signal "BOTTOM")
		(9 "F.Adhes" user "F.Adhesive")
		(11 "B.Adhes" user "B.Adhesive")
		(13 "F.Paste" user "Package Geometry/Pastemask Top")
		(15 "B.Paste" user "Package Geometry/Pastemask Bottom")
		(5 "F.SilkS" user "Ref Des/Silkscreen Top")
		(7 "B.SilkS" user "Ref Des/Silkscreen Bottom")
		(1 "F.Mask" user "Board Geometry/Soldermask Top")
		(3 "B.Mask" user "Board Geometry/Soldermask Bottom")
		(17 "Dwgs.User" user "User.Drawings")
		(19 "Cmts.User" user "User.Comments")
		(21 "Eco1.User" user "User.Eco1")
		(23 "Eco2.User" user "User.Eco2")
		(25 "Edge.Cuts" user "Board Geometry/Outline")
		(27 "Margin" user)
		(31 "F.CrtYd" user "Package Geometry/Place Bound Top")
		(29 "B.CrtYd" user "Package Geometry/Place Bound Bottom")
		(35 "F.Fab" user "Ref Des/Assembly Top")
		(33 "B.Fab" user "Ref Des/Assembly Bottom")
	)
	(footprint ""
		(layer "B.Cu")
		(at 139.954 -54.61 90)
		(property "Reference" "R250"
			(at 0.508 1.10363 270)
			(unlocked yes)
			(layer "B.SilkS")
			(effects
				(font
					(size 0.7874 0.5842)
					(thickness 0.1524)
				)
				(justify mirror)
			)
		)
		(property "Value" "VAL*"
			(at -0.02032 2.13233 90)
			(unlocked yes)
			(layer "B.Fab")
			(hide yes)
			(effects
				(font
					(size 0.7874 0.5842)
					(thickness 0.1524)
				)
				(justify mirror)
			)
		)
		(property "Tolerance" "TOL*"
			(at -0.044704 3.05435 90)
			(unlocked yes)
			(layer "Cmts.User")
			(hide yes)
			(effects
				(font
					(size 0.7874 0.5842)
					(thickness 0.1524)
				)
				(justify mirror)
			)
		)
		(property "User Part Number" "PARTNUM*"
			(at -0.02032 4.024884 90)
			(unlocked yes)
			(layer "Cmts.User")
			(hide yes)
			(effects
				(font
					(size 0.7874 0.5842)
					(thickness 0.1524)
				)
				(justify mirror)
			)
		)
		(property "Device Type" "RESISTOR-G155-100R0-J0,0OHM,-"
			(at -0.008382 1.210564 90)
			(unlocked yes)
			(layer "B.Fab")
			(hide yes)
			(effects
				(font
					(size 0.7874 0.5842)
					(thickness 0.1524)
				)
				(justify mirror)
			)
		)
		(duplicate_pad_numbers_are_jumpers no)
		(fp_line
			(start 1.143 -0.5588)
			(end 1.143 0.5588)
			(stroke
				(width 0.1)
				(type default)
			)
			(layer "B.SilkS")
		)
		(fp_line
			(start -1.143 -0.5588)
			(end 1.143 -0.5588)
			(stroke
				(width 0.1)
				(type default)
			)
			(layer "B.SilkS")
		)
		(fp_line
			(start 1.143 0.5588)
			(end -1.143 0.5588)
			(stroke
				(width 0.1)
				(type default)
			)
			(layer "B.SilkS")
		)
		(fp_line
			(start -1.143 0.5588)
			(end -1.143 -0.5588)
			(stroke
				(width 0.1)
				(type default)
			)
			(layer "B.SilkS")
		)
		(fp_poly
			(pts
				(xy 1.143 0.5588) (xy -1.143 0.5588) (xy -1.143 -0.5588) (xy 1.143 -0.5588)
			)
			(stroke
				(width 0)
				(type default)
			)
			(fill no)
			(layer "B.CrtYd")
		)
		(fp_line
			(start 0.508 -0.3048)
			(end 0.508 0.3048)
			(stroke
				(width 0.1)
				(type default)
			)
			(layer "B.Fab")
		)
		(fp_line
			(start -0.508 -0.3048)
			(end 0.508 -0.3048)
			(stroke
				(width 0.1)
				(type default)
			)
			(layer "B.Fab")
		)
		(fp_line
			(start 0.508 0.3048)
			(end -0.508 0.3048)
			(stroke
				(width 0.1)
				(type default)
			)
			(layer "B.Fab")
		)
		(fp_line
			(start -0.508 0.3048)
			(end -0.508 -0.3048)
			(stroke
				(width 0.1)
				(type default)
			)
			(layer "B.Fab")
		)
		(pad "1" smd rect
			(at 0.5334 0 270)
			(size 0.7112 0.6096)
			(layers "B.Cu" "B.Mask" "B.Paste")
			(net "XP1R0V_BT")
		)
		(pad "2" smd rect
			(at -0.5334 0 270)
			(size 0.7112 0.6096)
			(layers "B.Cu" "B.Mask" "B.Paste")
			(net "UNNAMED_523_CAPACITOR_I24_1")
		)
		(zone
			(layer "B.Cu")
			(hatch none 0.5)
			(connect_pads
				(clearance 0)
			)
			(min_thickness 0.25)
			(keepout
				(tracks allowed)
				(vias not_allowed)
				(pads allowed)
				(copperpour not_allowed)
				(footprints allowed)
			)
			(placement
				(enabled no)
				(sheetname "")
			)
			(fill
				(thermal_gap 0.5)
				(thermal_bridge_width 0.5)
				(island_removal_mode 0)
			)
			(polygon
				(pts
					(xy 140.2588 -54.6862) (xy 139.6492 -54.6862) (xy 139.6492 -54.5338) (xy 140.2588 -54.5338)
				)
			)
		)
		(zone
			(layer "B.Cu")
			(hatch none 0.5)
			(connect_pads
				(clearance 0)
			)
			(min_thickness 0.25)
			(keepout
				(tracks not_allowed)
				(vias allowed)
				(pads allowed)
				(copperpour not_allowed)
				(footprints allowed)
			)
			(placement
				(enabled no)
				(sheetname "")
			)
			(fill
				(thermal_gap 0.5)
				(thermal_bridge_width 0.5)
				(island_removal_mode 0)
			)
			(polygon
				(pts
					(xy 140.2588 -54.6862) (xy 139.6492 -54.6862) (xy 139.6492 -54.5338) (xy 140.2588 -54.5338)
				)
			)
		)
	)
	(footprint ""
		(layer "B.Cu")
		(at 117.346984 -32.822896 180)
		(property "Reference" "R275"
			(at -0.509016 -1.231646 0)
			(unlocked yes)
			(layer "B.SilkS")
			(effects
				(font
					(size 0.635 0.4064)
					(thickness 0.1524)
				)
				(justify mirror)
			)
		)
		(property "Value" "VAL*"
			(at 0 3.718306 180)
			(unlocked yes)
			(layer "B.Fab")
			(hide yes)
			(effects
				(font
					(size 0.7874 0.5842)
					(thickness 0.127)
				)
				(justify mirror)
			)
		)
		(property "Tolerance" "TOL*"
			(at 0 4.861306 180)
			(unlocked yes)
			(layer "Cmts.User")
			(hide yes)
			(effects
				(font
					(size 0.7874 0.5842)
					(thickness 0.127)
				)
				(justify mirror)
			)
		)
		(property "User Part Number" "PARTNUM*"
			(at 0 2.575306 180)
			(unlocked yes)
			(layer "Cmts.User")
			(hide yes)
			(effects
				(font
					(size 0.7874 0.5842)
					(thickness 0.127)
				)
				(justify mirror)
			)
		)
		(property "Device Type" "RESISTOR-G155-11000-01,100OHM,A"
			(at 0 1.432306 180)
			(unlocked yes)
			(layer "B.Fab")
			(hide yes)
			(effects
				(font
					(size 0.7874 0.5842)
					(thickness 0.127)
				)
				(justify mirror)
			)
		)
		(duplicate_pad_numbers_are_jumpers no)
		(fp_line
			(start 0.970026 0.4699)
			(end 0.970026 -0.4699)
			(stroke
				(width 0.1)
				(type default)
			)
			(layer "B.SilkS")
		)
		(fp_line
			(start 0.970026 -0.4699)
			(end -0.970026 -0.4699)
			(stroke
				(width 0.1)
				(type default)
			)
			(layer "B.SilkS")
		)
		(fp_line
			(start -0.970026 0.4699)
			(end 0.970026 0.4699)
			(stroke
				(width 0.1)
				(type default)
			)
			(layer "B.SilkS")
		)
		(fp_line
			(start -0.970026 -0.4699)
			(end -0.970026 0.4699)
			(stroke
				(width 0.1)
				(type default)
			)
			(layer "B.SilkS")
		)
		(fp_poly
			(pts
				(xy 0.970026 0.4699) (xy -0.970026 0.4699) (xy -0.970026 -0.4699) (xy 0.970026 -0.4699)
			)
			(stroke
				(width 0)
				(type default)
			)
			(fill no)
			(layer "B.CrtYd")
		)
		(fp_line
			(start 0.508 0.3048)
			(end 0.508 -0.3048)
			(stroke
				(width 0.1)
				(type default)
			)
			(layer "B.Fab")
		)
		(fp_line
			(start 0.508 -0.3048)
			(end -0.508 -0.3048)
			(stroke
				(width 0.1)
				(type default)
			)
			(layer "B.Fab")
		)
		(fp_line
			(start -0.508 0.3048)
			(end 0.508 0.3048)
			(stroke
				(width 0.1)
				(type default)
			)
			(layer "B.Fab")
		)
		(fp_line
			(start -0.508 -0.3048)
			(end -0.508 0.3048)
			(stroke
				(width 0.1)
				(type default)
			)
			(layer "B.Fab")
		)
		(pad "1" smd circle
			(at 0.500126 0)
			(size 0.635 0.635)
			(layers "B.Cu" "B.Mask" "B.Paste")
			(net "FPGA_IN_MAC_PPS_OUTP")
		)
		(pad "2" smd circle
			(at -0.500126 0)
			(size 0.635 0.635)
			(layers "B.Cu" "B.Mask" "B.Paste")
			(net "FPGA_IN_MAC_PPS_OUTN")
		)
	)
)
